# S9S_MB_2U (Grand Teton) — schematic netlist excerpt (pin names and nets, part order shuffled) for the footprints in the layout excerpt that follows; sources: Cadence DE-HDL packaged netlist, KiCad conversion of 03242023_DA0F0TMBIJ0_F0T_Motherboard_J_brd_V01_OCP.brd

PR143  Q_RES  0 5% CHIP  pkg 0402LF  page 269 : A = PVCCIN_CPU0_VOS5 ; B = PVCCIN_CPU0
PR1325  Q_RES  0 5% CHIP  pkg 0402LF  page 272 : A = PVCCFA_EHV_FIVRA_CPU0_VOS4 ; B = PVCCFA_EHV_FIVRA_CPU0

(kicad_pcb
	(version 20260206)
	(generator "pcbnew")
	(generator_version "10.0")
	(general
		(thickness 1.6)
		(legacy_teardrops no)
	)
	(paper "A4")
	(title_block
		(title "03242023_DA0F0TMBIJ0_F0T_Motherboard_J_brd_V01_OCP.brd")
		(comment 1 "Grand Teton / footprints 5113-5114 of 6105")
	)
	(layers
		(0 "F.Cu" signal "TOP")
		(4 "In1.Cu" signal "GND")
		(6 "In2.Cu" signal "IN1")
		(8 "In3.Cu" signal "GND1")
		(10 "In4.Cu" signal "IN2")
		(12 "In5.Cu" signal "GND2")
		(14 "In6.Cu" signal "IN3")
		(16 "In7.Cu" signal "GND3")
		(18 "In8.Cu" signal "VCC")
		(20 "In9.Cu" signal "VCC1")
		(22 "In10.Cu" signal "GND4")
		(24 "In11.Cu" signal "IN4")
		(26 "In12.Cu" signal "GND5")
		(28 "In13.Cu" signal "IN5")
		(30 "In14.Cu" signal "GND6")
		(32 "In15.Cu" signal "IN6")
		(34 "In16.Cu" signal "GND7")
		(2 "B.Cu" signal "BOTTOM")
		(9 "F.Adhes" user "F.Adhesive")
		(11 "B.Adhes" user "B.Adhesive")
		(13 "F.Paste" user "Package Geometry/Pastemask Top")
		(15 "B.Paste" user "Package Geometry/Pastemask Bottom")
		(5 "F.SilkS" user "Ref Des/Silkscreen Top")
		(7 "B.SilkS" user "Ref Des/Silkscreen Bottom")
		(1 "F.Mask" user "Board Geometry/Soldermask Top")
		(3 "B.Mask" user "Board Geometry/Soldermask Bottom")
		(17 "Dwgs.User" user "User.Drawings")
		(19 "Cmts.User" user "User.Comments")
		(21 "Eco1.User" user "User.Eco1")
		(23 "Eco2.User" user "User.Eco2")
		(25 "Edge.Cuts" user "Board Geometry/Outline")
		(27 "Margin" user)
		(31 "F.CrtYd" user "Package Geometry/Place Bound Top")
		(29 "B.CrtYd" user "Package Geometry/Place Bound Bottom")
		(35 "F.Fab" user "Ref Des/Assembly Top")
		(33 "B.Fab" user "Ref Des/Assembly Bottom")
	)
	(footprint ""
		(layer "B.Cu")
		(at 374.00484 -339.602572 -90)
		(property "Reference" "PR143"
			(at 0 0 90)
			(layer "B.SilkS")
			(hide yes)
			(effects
				(font
					(size 1.27 1.27)
				)
				(justify mirror)
			)
		)
		(property "Value" ""
			(at 0 0 90)
			(layer "B.Fab")
			(effects
				(font
					(size 1.27 1.27)
				)
				(justify mirror)
			)
		)
		(duplicate_pad_numbers_are_jumpers no)
		(fp_line
			(start -0.7874 0.4064)
			(end 0.7874 0.4064)
			(stroke
				(width 0.1524)
				(type default)
			)
			(layer "B.SilkS")
		)
		(fp_line
			(start 0.7874 0.4064)
			(end 0.7874 -0.4064)
			(stroke
				(width 0.1524)
				(type default)
			)
			(layer "B.SilkS")
		)
		(fp_line
			(start -0.7874 -0.4064)
			(end -0.7874 0.4064)
			(stroke
				(width 0.1524)
				(type default)
			)
			(layer "B.SilkS")
		)
		(fp_line
			(start 0.7874 -0.4064)
			(end -0.7874 -0.4064)
			(stroke
				(width 0.1524)
				(type default)
			)
			(layer "B.SilkS")
		)
		(fp_line
			(start -0.67945 0.3048)
			(end -0.120396 0.3048)
			(stroke
				(width 0.1)
				(type default)
			)
			(layer "B.Fab")
		)
		(fp_line
			(start -0.120396 0.3048)
			(end -0.120396 0.2794)
			(stroke
				(width 0.1)
				(type default)
			)
			(layer "B.Fab")
		)
		(fp_line
			(start 0.12065 0.3048)
			(end 0.67945 0.3048)
			(stroke
				(width 0.1)
				(type default)
			)
			(layer "B.Fab")
		)
		(fp_line
			(start 0.67945 0.3048)
			(end 0.67945 -0.305054)
			(stroke
				(width 0.1)
				(type default)
			)
			(layer "B.Fab")
		)
		(fp_line
			(start -0.120396 0.2794)
			(end 0.12065 0.2794)
			(stroke
				(width 0.1)
				(type default)
			)
			(layer "B.Fab")
		)
		(fp_line
			(start 0.12065 0.2794)
			(end 0.12065 0.3048)
			(stroke
				(width 0.1)
				(type default)
			)
			(layer "B.Fab")
		)
		(fp_line
			(start -0.12065 -0.2794)
			(end -0.12065 -0.3048)
			(stroke
				(width 0.1)
				(type default)
			)
			(layer "B.Fab")
		)
		(fp_line
			(start 0.12065 -0.2794)
			(end -0.12065 -0.2794)
			(stroke
				(width 0.1)
				(type default)
			)
			(layer "B.Fab")
		)
		(fp_line
			(start -0.67945 -0.3048)
			(end -0.67945 0.3048)
			(stroke
				(width 0.1)
				(type default)
			)
			(layer "B.Fab")
		)
		(fp_line
			(start -0.12065 -0.3048)
			(end -0.67945 -0.3048)
			(stroke
				(width 0.1)
				(type default)
			)
			(layer "B.Fab")
		)
		(fp_line
			(start 0.12065 -0.305054)
			(end 0.12065 -0.2794)
			(stroke
				(width 0.1)
				(type default)
			)
			(layer "B.Fab")
		)
		(fp_line
			(start 0.67945 -0.305054)
			(end 0.12065 -0.305054)
			(stroke
				(width 0.1)
				(type default)
			)
			(layer "B.Fab")
		)
		(pad "1" smd circle
			(at 0.40005 0 90)
			(size 0 0)
			(layers "B.Cu" "B.Mask" "B.Paste")
			(net "PVCCIN_CPU0_VOS5")
		)
		(pad "2" smd circle
			(at -0.40005 0 90)
			(size 0 0)
			(layers "B.Cu" "B.Mask" "B.Paste")
			(net "PVCCIN_CPU0")
		)
	)
	(footprint ""
		(layer "B.Cu")
		(at 284.925262 -365.653066 -90)
		(property "Reference" "PR1325"
			(at 0 0 90)
			(layer "B.SilkS")
			(hide yes)
			(effects
				(font
					(size 1.27 1.27)
				)
				(justify mirror)
			)
		)
		(property "Value" ""
			(at 0 0 90)
			(layer "B.Fab")
			(effects
				(font
					(size 1.27 1.27)
				)
				(justify mirror)
			)
		)
		(duplicate_pad_numbers_are_jumpers no)
		(fp_line
			(start -0.7874 0.4064)
			(end 0.7874 0.4064)
			(stroke
				(width 0.1524)
				(type default)
			)
			(layer "B.SilkS")
		)
		(fp_line
			(start 0.7874 0.4064)
			(end 0.7874 -0.4064)
			(stroke
				(width 0.1524)
				(type default)
			)
			(layer "B.SilkS")
		)
		(fp_line
			(start -0.7874 -0.4064)
			(end -0.7874 0.4064)
			(stroke
				(width 0.1524)
				(type default)
			)
			(layer "B.SilkS")
		)
		(fp_line
			(start 0.7874 -0.4064)
			(end -0.7874 -0.4064)
			(stroke
				(width 0.1524)
				(type default)
			)
			(layer "B.SilkS")
		)
		(fp_line
			(start -0.67945 0.3048)
			(end -0.120396 0.3048)
			(stroke
				(width 0.1)
				(type default)
			)
			(layer "B.Fab")
		)
		(fp_line
			(start -0.120396 0.3048)
			(end -0.120396 0.2794)
			(stroke
				(width 0.1)
				(type default)
			)
			(layer "B.Fab")
		)
		(fp_line
			(start 0.12065 0.3048)
			(end 0.67945 0.3048)
			(stroke
				(width 0.1)
				(type default)
			)
			(layer "B.Fab")
		)
		(fp_line
			(start 0.67945 0.3048)
			(end 0.67945 -0.305054)
			(stroke
				(width 0.1)
				(type default)
			)
			(layer "B.Fab")
		)
		(fp_line
			(start -0.120396 0.2794)
			(end 0.12065 0.2794)
			(stroke
				(width 0.1)
				(type default)
			)
			(layer "B.Fab")
		)
		(fp_line
			(start 0.12065 0.2794)
			(end 0.12065 0.3048)
			(stroke
				(width 0.1)
				(type default)
			)
			(layer "B.Fab")
		)
		(fp_line
			(start -0.12065 -0.2794)
			(end -0.12065 -0.3048)
			(stroke
				(width 0.1)
				(type default)
			)
			(layer "B.Fab")
		)
		(fp_line
			(start 0.12065 -0.2794)
			(end -0.12065 -0.2794)
			(stroke
				(width 0.1)
				(type default)
			)
			(layer "B.Fab")
		)
		(fp_line
			(start -0.67945 -0.3048)
			(end -0.67945 0.3048)
			(stroke
				(width 0.1)
				(type default)
			)
			(layer "B.Fab")
		)
		(fp_line
			(start -0.12065 -0.3048)
			(end -0.67945 -0.3048)
			(stroke
				(width 0.1)
				(type default)
			)
			(layer "B.Fab")
		)
		(fp_line
			(start 0.12065 -0.305054)
			(end 0.12065 -0.2794)
			(stroke
				(width 0.1)
				(type default)
			)
			(layer "B.Fab")
		)
		(fp_line
			(start 0.67945 -0.305054)
			(end 0.12065 -0.305054)
			(stroke
				(width 0.1)
				(type default)
			)
			(layer "B.Fab")
		)
		(pad "1" smd circle
			(at 0.40005 0 90)
			(size 0 0)
			(layers "B.Cu" "B.Mask" "B.Paste")
			(net "PVCCFA_EHV_FIVRA_CPU0_VOS4")
		)
		(pad "2" smd circle
			(at -0.40005 0 90)
			(size 0 0)
			(layers "B.Cu" "B.Mask" "B.Paste")
			(net "PVCCFA_EHV_FIVRA_CPU0")
		)
	)
)
